(kicad_pcb
	(version 20260206)
	(generator "pcbnew")
	(generator_version "10.0")
	(general
		(thickness 1.6)
		(legacy_teardrops no)
	)
	(paper "A4")
	(title_block
		(title "03242023_DA0F0TMBIJ0_F0T_Motherboard_J_brd_V01_OCP.brd")
		(comment 1 "Grand Teton / footprints 2781-2787 of 6105")
	)
	(layers
		(0 "F.Cu" signal "TOP")
		(4 "In1.Cu" signal "GND")
		(6 "In2.Cu" signal "IN1")
		(8 "In3.Cu" signal "GND1")
		(10 "In4.Cu" signal "IN2")
		(12 "In5.Cu" signal "GND2")
		(14 "In6.Cu" signal "IN3")
		(16 "In7.Cu" signal "GND3")
		(18 "In8.Cu" signal "VCC")
		(20 "In9.Cu" signal "VCC1")
		(22 "In10.Cu" signal "GND4")
		(24 "In11.Cu" signal "IN4")
		(26 "In12.Cu" signal "GND5")
		(28 "In13.Cu" signal "IN5")
		(30 "In14.Cu" signal "GND6")
		(32 "In15.Cu" signal "IN6")
		(34 "In16.Cu" signal "GND7")
		(2 "B.Cu" signal "BOTTOM")
		(9 "F.Adhes" user "F.Adhesive")
		(11 "B.Adhes" user "B.Adhesive")
		(13 "F.Paste" user "Package Geometry/Pastemask Top")
		(15 "B.Paste" user "Package Geometry/Pastemask Bottom")
		(5 "F.SilkS" user "Ref Des/Silkscreen Top")
		(7 "B.SilkS" user "Ref Des/Silkscreen Bottom")
		(1 "F.Mask" user "Board Geometry/Soldermask Top")
		(3 "B.Mask" user "Board Geometry/Soldermask Bottom")
		(17 "Dwgs.User" user "User.Drawings")
		(19 "Cmts.User" user "User.Comments")
		(21 "Eco1.User" user "User.Eco1")
		(23 "Eco2.User" user "User.Eco2")
		(25 "Edge.Cuts" user "Board Geometry/Outline")
		(27 "Margin" user)
		(31 "F.CrtYd" user "Package Geometry/Place Bound Top")
		(29 "B.CrtYd" user "Package Geometry/Place Bound Bottom")
		(35 "F.Fab" user "Ref Des/Assembly Top")
		(33 "B.Fab" user "Ref Des/Assembly Bottom")
	)
	(footprint ""
		(layer "F.Cu")
		(at 148.98243 -79.139034)
		(property "Reference" "R3130"
			(at 0 0 0)
			(layer "F.SilkS")
			(hide yes)
			(effects
				(font
					(size 1.27 1.27)
				)
			)
		)
		(property "Value" ""
			(at 0 0 0)
			(layer "F.Fab")
			(effects
				(font
					(size 1.27 1.27)
				)
			)
		)
		(duplicate_pad_numbers_are_jumpers no)
		(fp_line
			(start -0.7874 -0.4064)
			(end 0.7874 -0.4064)
			(stroke
				(width 0.1524)
				(type default)
			)
			(layer "F.SilkS")
		)
		(fp_line
			(start -0.7874 0.4064)
			(end -0.7874 -0.4064)
			(stroke
				(width 0.1524)
				(type default)
			)
			(layer "F.SilkS")
		)
		(fp_line
			(start 0.7874 -0.4064)
			(end 0.7874 0.4064)
			(stroke
				(width 0.1524)
				(type default)
			)
			(layer "F.SilkS")
		)
		(fp_line
			(start 0.7874 0.4064)
			(end -0.7874 0.4064)
			(stroke
				(width 0.1524)
				(type default)
			)
			(layer "F.SilkS")
		)
		(fp_line
			(start -0.67945 -0.305054)
			(end -0.12065 -0.305054)
			(stroke
				(width 0.1)
				(type default)
			)
			(layer "F.Fab")
		)
		(fp_line
			(start -0.67945 0.3048)
			(end -0.67945 -0.305054)
			(stroke
				(width 0.1)
				(type default)
			)
			(layer "F.Fab")
		)
		(fp_line
			(start -0.12065 -0.305054)
			(end -0.12065 -0.2794)
			(stroke
				(width 0.1)
				(type default)
			)
			(layer "F.Fab")
		)
		(fp_line
			(start -0.12065 -0.2794)
			(end 0.12065 -0.2794)
			(stroke
				(width 0.1)
				(type default)
			)
			(layer "F.Fab")
		)
		(fp_line
			(start -0.12065 0.2794)
			(end -0.12065 0.3048)
			(stroke
				(width 0.1)
				(type default)
			)
			(layer "F.Fab")
		)
		(fp_line
			(start -0.12065 0.3048)
			(end -0.67945 0.3048)
			(stroke
				(width 0.1)
				(type default)
			)
			(layer "F.Fab")
		)
		(fp_line
			(start 0.120396 0.2794)
			(end -0.12065 0.2794)
			(stroke
				(width 0.1)
				(type default)
			)
			(layer "F.Fab")
		)
		(fp_line
			(start 0.120396 0.3048)
			(end 0.120396 0.2794)
			(stroke
				(width 0.1)
				(type default)
			)
			(layer "F.Fab")
		)
		(fp_line
			(start 0.12065 -0.3048)
			(end 0.67945 -0.3048)
			(stroke
				(width 0.1)
				(type default)
			)
			(layer "F.Fab")
		)
		(fp_line
			(start 0.12065 -0.2794)
			(end 0.12065 -0.3048)
			(stroke
				(width 0.1)
				(type default)
			)
			(layer "F.Fab")
		)
		(fp_line
			(start 0.67945 -0.3048)
			(end 0.67945 0.3048)
			(stroke
				(width 0.1)
				(type default)
			)
			(layer "F.Fab")
		)
		(fp_line
			(start 0.67945 0.3048)
			(end 0.120396 0.3048)
			(stroke
				(width 0.1)
				(type default)
			)
			(layer "F.Fab")
		)
		(pad "1" smd circle
			(at -0.40005 0)
			(size 0 0)
			(layers "F.Cu" "F.Mask" "F.Paste")
			(net "P3V3_AUX")
		)
		(pad "2" smd circle
			(at 0.40005 0)
			(size 0 0)
			(layers "F.Cu" "F.Mask" "F.Paste")
			(net "PCA9543_S3M_INT2_N")
		)
	)
	(footprint ""
		(layer "F.Cu")
		(at 148.613114 -402.371052 -90)
		(property "Reference" "C760"
			(at 0 0 270)
			(layer "F.SilkS")
			(hide yes)
			(effects
				(font
					(size 1.27 1.27)
				)
			)
		)
		(property "Value" ""
			(at 0 0 270)
			(layer "F.Fab")
			(effects
				(font
					(size 1.27 1.27)
				)
			)
		)
		(duplicate_pad_numbers_are_jumpers no)
		(fp_line
			(start -0.299974 0.150114)
			(end -0.299974 -0.150114)
			(stroke
				(width 0.1)
				(type default)
			)
			(layer "F.Fab")
		)
		(fp_line
			(start 0.299974 0.150114)
			(end -0.299974 0.150114)
			(stroke
				(width 0.1)
				(type default)
			)
			(layer "F.Fab")
		)
		(fp_line
			(start -0.299974 -0.150114)
			(end 0.299974 -0.150114)
			(stroke
				(width 0.1)
				(type default)
			)
			(layer "F.Fab")
		)
		(fp_line
			(start 0.299974 -0.150114)
			(end 0.299974 0.150114)
			(stroke
				(width 0.1)
				(type default)
			)
			(layer "F.Fab")
		)
		(pad "1" smd rect
			(at -0.2667 0 270)
			(size 0.3048 0.381)
			(layers "F.Cu" "F.Mask" "F.Paste")
			(net "P5E_CPU1_PE2_TX_C_DN<6>")
		)
		(pad "2" smd rect
			(at 0.2667 0 270)
			(size 0.3048 0.381)
			(layers "F.Cu" "F.Mask" "F.Paste")
			(net "P5E_CPU1_PE2_TX_DN<6>")
		)
	)
	(footprint ""
		(layer "F.Cu")
		(at 390.42594 -343.018872 -90)
		(property "Reference" "PC230_P0_8"
			(at 0 0 270)
			(layer "F.SilkS")
			(hide yes)
			(effects
				(font
					(size 1.27 1.27)
				)
			)
		)
		(property "Value" ""
			(at 0 0 270)
			(layer "F.Fab")
			(effects
				(font
					(size 1.27 1.27)
				)
			)
		)
		(duplicate_pad_numbers_are_jumpers no)
		(fp_line
			(start -0.7874 0.4064)
			(end -0.7874 -0.4064)
			(stroke
				(width 0.1524)
				(type default)
			)
			(layer "F.SilkS")
		)
		(fp_line
			(start 0.7874 0.4064)
			(end -0.7874 0.4064)
			(stroke
				(width 0.1524)
				(type default)
			)
			(layer "F.SilkS")
		)
		(fp_line
			(start -0.7874 -0.4064)
			(end 0.7874 -0.4064)
			(stroke
				(width 0.1524)
				(type default)
			)
			(layer "F.SilkS")
		)
		(fp_line
			(start 0.7874 -0.4064)
			(end 0.7874 0.4064)
			(stroke
				(width 0.1524)
				(type default)
			)
			(layer "F.SilkS")
		)
		(fp_line
			(start -0.67945 0.3048)
			(end -0.67945 -0.305054)
			(stroke
				(width 0.1)
				(type default)
			)
			(layer "F.Fab")
		)
		(fp_line
			(start -0.12065 0.3048)
			(end -0.67945 0.3048)
			(stroke
				(width 0.1)
				(type default)
			)
			(layer "F.Fab")
		)
		(fp_line
			(start 0.120396 0.3048)
			(end 0.120396 0.2794)
			(stroke
				(width 0.1)
				(type default)
			)
			(layer "F.Fab")
		)
		(fp_line
			(start 0.67945 0.3048)
			(end 0.120396 0.3048)
			(stroke
				(width 0.1)
				(type default)
			)
			(layer "F.Fab")
		)
		(fp_line
			(start -0.12065 0.2794)
			(end -0.12065 0.3048)
			(stroke
				(width 0.1)
				(type default)
			)
			(layer "F.Fab")
		)
		(fp_line
			(start 0.120396 0.2794)
			(end -0.12065 0.2794)
			(stroke
				(width 0.1)
				(type default)
			)
			(layer "F.Fab")
		)
		(fp_line
			(start -0.12065 -0.2794)
			(end 0.12065 -0.2794)
			(stroke
				(width 0.1)
				(type default)
			)
			(layer "F.Fab")
		)
		(fp_line
			(start 0.12065 -0.2794)
			(end 0.12065 -0.3048)
			(stroke
				(width 0.1)
				(type default)
			)
			(layer "F.Fab")
		)
		(fp_line
			(start 0.12065 -0.3048)
			(end 0.67945 -0.3048)
			(stroke
				(width 0.1)
				(type default)
			)
			(layer "F.Fab")
		)
		(fp_line
			(start 0.67945 -0.3048)
			(end 0.67945 0.3048)
			(stroke
				(width 0.1)
				(type default)
			)
			(layer "F.Fab")
		)
		(fp_line
			(start -0.67945 -0.305054)
			(end -0.12065 -0.305054)
			(stroke
				(width 0.1)
				(type default)
			)
			(layer "F.Fab")
		)
		(fp_line
			(start -0.12065 -0.305054)
			(end -0.12065 -0.2794)
			(stroke
				(width 0.1)
				(type default)
			)
			(layer "F.Fab")
		)
		(pad "1" smd circle
			(at -0.40005 0 270)
			(size 0 0)
			(layers "F.Cu" "F.Mask" "F.Paste")
			(net "SW_P12V_PVCCIN_CPU0_FLT")
		)
		(pad "2" smd circle
			(at 0.40005 0 270)
			(size 0 0)
			(layers "F.Cu" "F.Mask" "F.Paste")
			(net "GND")
		)
	)
	(footprint ""
		(layer "F.Cu")
		(at 276.80666 -424.424602 180)
		(property "Reference" "R4671"
			(at 0 0 180)
			(layer "F.SilkS")
			(hide yes)
			(effects
				(font
					(size 1.27 1.27)
				)
			)
		)
		(property "Value" ""
			(at 0 0 180)
			(layer "F.Fab")
			(effects
				(font
					(size 1.27 1.27)
				)
			)
		)
		(duplicate_pad_numbers_are_jumpers no)
		(fp_line
			(start 0.7874 0.4064)
			(end -0.7874 0.4064)
			(stroke
				(width 0.1524)
				(type default)
			)
			(layer "F.SilkS")
		)
		(fp_line
			(start 0.7874 -0.4064)
			(end 0.7874 0.4064)
			(stroke
				(width 0.1524)
				(type default)
			)
			(layer "F.SilkS")
		)
		(fp_line
			(start -0.7874 0.4064)
			(end -0.7874 -0.4064)
			(stroke
				(width 0.1524)
				(type default)
			)
			(layer "F.SilkS")
		)
		(fp_line
			(start -0.7874 -0.4064)
			(end 0.7874 -0.4064)
			(stroke
				(width 0.1524)
				(type default)
			)
			(layer "F.SilkS")
		)
		(fp_line
			(start 0.67945 0.3048)
			(end 0.120396 0.3048)
			(stroke
				(width 0.1)
				(type default)
			)
			(layer "F.Fab")
		)
		(fp_line
			(start 0.67945 -0.3048)
			(end 0.67945 0.3048)
			(stroke
				(width 0.1)
				(type default)
			)
			(layer "F.Fab")
		)
		(fp_line
			(start 0.12065 -0.2794)
			(end 0.12065 -0.3048)
			(stroke
				(width 0.1)
				(type default)
			)
			(layer "F.Fab")
		)
		(fp_line
			(start 0.12065 -0.3048)
			(end 0.67945 -0.3048)
			(stroke
				(width 0.1)
				(type default)
			)
			(layer "F.Fab")
		)
		(fp_line
			(start 0.120396 0.3048)
			(end 0.120396 0.2794)
			(stroke
				(width 0.1)
				(type default)
			)
			(layer "F.Fab")
		)
		(fp_line
			(start 0.120396 0.2794)
			(end -0.12065 0.2794)
			(stroke
				(width 0.1)
				(type default)
			)
			(layer "F.Fab")
		)
		(fp_line
			(start -0.12065 0.3048)
			(end -0.67945 0.3048)
			(stroke
				(width 0.1)
				(type default)
			)
			(layer "F.Fab")
		)
		(fp_line
			(start -0.12065 0.2794)
			(end -0.12065 0.3048)
			(stroke
				(width 0.1)
				(type default)
			)
			(layer "F.Fab")
		)
		(fp_line
			(start -0.12065 -0.2794)
			(end 0.12065 -0.2794)
			(stroke
				(width 0.1)
				(type default)
			)
			(layer "F.Fab")
		)
		(fp_line
			(start -0.12065 -0.305054)
			(end -0.12065 -0.2794)
			(stroke
				(width 0.1)
				(type default)
			)
			(layer "F.Fab")
		)
		(fp_line
			(start -0.67945 0.3048)
			(end -0.67945 -0.305054)
			(stroke
				(width 0.1)
				(type default)
			)
			(layer "F.Fab")
		)
		(fp_line
			(start -0.67945 -0.305054)
			(end -0.12065 -0.305054)
			(stroke
				(width 0.1)
				(type default)
			)
			(layer "F.Fab")
		)
		(pad "1" smd circle
			(at -0.40005 0 180)
			(size 0 0)
			(layers "F.Cu" "F.Mask" "F.Paste")
			(net "P3V3_AUX")
		)
		(pad "2" smd circle
			(at 0.40005 0 180)
			(size 0 0)
			(layers "F.Cu" "F.Mask" "F.Paste")
			(net "HSC_D_OC")
		)
	)
	(footprint ""
		(layer "F.Cu")
		(at 426.73016 -143.675608 90)
		(property "Reference" "PR4221"
			(at 0 0 90)
			(layer "F.SilkS")
			(hide yes)
			(effects
				(font
					(size 1.27 1.27)
				)
			)
		)
		(property "Value" ""
			(at 0 0 90)
			(layer "F.Fab")
			(effects
				(font
					(size 1.27 1.27)
				)
			)
		)
		(duplicate_pad_numbers_are_jumpers no)
		(fp_line
			(start 0.7874 -0.4064)
			(end 0.7874 0.4064)
			(stroke
				(width 0.1524)
				(type default)
			)
			(layer "F.SilkS")
		)
		(fp_line
			(start -0.7874 -0.4064)
			(end 0.7874 -0.4064)
			(stroke
				(width 0.1524)
				(type default)
			)
			(layer "F.SilkS")
		)
		(fp_line
			(start 0.7874 0.4064)
			(end -0.7874 0.4064)
			(stroke
				(width 0.1524)
				(type default)
			)
			(layer "F.SilkS")
		)
		(fp_line
			(start -0.7874 0.4064)
			(end -0.7874 -0.4064)
			(stroke
				(width 0.1524)
				(type default)
			)
			(layer "F.SilkS")
		)
		(fp_line
			(start -0.12065 -0.305054)
			(end -0.12065 -0.2794)
			(stroke
				(width 0.1)
				(type default)
			)
			(layer "F.Fab")
		)
		(fp_line
			(start -0.67945 -0.305054)
			(end -0.12065 -0.305054)
			(stroke
				(width 0.1)
				(type default)
			)
			(layer "F.Fab")
		)
		(fp_line
			(start 0.67945 -0.3048)
			(end 0.67945 0.3048)
			(stroke
				(width 0.1)
				(type default)
			)
			(layer "F.Fab")
		)
		(fp_line
			(start 0.12065 -0.3048)
			(end 0.67945 -0.3048)
			(stroke
				(width 0.1)
				(type default)
			)
			(layer "F.Fab")
		)
		(fp_line
			(start 0.12065 -0.2794)
			(end 0.12065 -0.3048)
			(stroke
				(width 0.1)
				(type default)
			)
			(layer "F.Fab")
		)
		(fp_line
			(start -0.12065 -0.2794)
			(end 0.12065 -0.2794)
			(stroke
				(width 0.1)
				(type default)
			)
			(layer "F.Fab")
		)
		(fp_line
			(start 0.120396 0.2794)
			(end -0.12065 0.2794)
			(stroke
				(width 0.1)
				(type default)
			)
			(layer "F.Fab")
		)
		(fp_line
			(start -0.12065 0.2794)
			(end -0.12065 0.3048)
			(stroke
				(width 0.1)
				(type default)
			)
			(layer "F.Fab")
		)
		(fp_line
			(start 0.67945 0.3048)
			(end 0.120396 0.3048)
			(stroke
				(width 0.1)
				(type default)
			)
			(layer "F.Fab")
		)
		(fp_line
			(start 0.120396 0.3048)
			(end 0.120396 0.2794)
			(stroke
				(width 0.1)
				(type default)
			)
			(layer "F.Fab")
		)
		(fp_line
			(start -0.12065 0.3048)
			(end -0.67945 0.3048)
			(stroke
				(width 0.1)
				(type default)
			)
			(layer "F.Fab")
		)
		(fp_line
			(start -0.67945 0.3048)
			(end -0.67945 -0.305054)
			(stroke
				(width 0.1)
				(type default)
			)
			(layer "F.Fab")
		)
		(pad "1" smd circle
			(at -0.40005 0 90)
			(size 0 0)
			(layers "F.Cu" "F.Mask" "F.Paste")
			(net "NC_PVCCINFAON_CPU0_ACSP3")
		)
		(pad "2" smd circle
			(at 0.40005 0 90)
			(size 0 0)
			(layers "F.Cu" "F.Mask" "F.Paste")
			(net "GND")
		)
	)
	(footprint ""
		(layer "F.Cu")
		(at 163.50488 -436.463948)
		(property "Reference" "R3451"
			(at 0 0 0)
			(layer "F.SilkS")
			(hide yes)
			(effects
				(font
					(size 1.27 1.27)
				)
			)
		)
		(property "Value" ""
			(at 0 0 0)
			(layer "F.Fab")
			(effects
				(font
					(size 1.27 1.27)
				)
			)
		)
		(duplicate_pad_numbers_are_jumpers no)
		(fp_line
			(start -0.7874 -0.4064)
			(end 0.7874 -0.4064)
			(stroke
				(width 0.1524)
				(type default)
			)
			(layer "F.SilkS")
		)
		(fp_line
			(start -0.7874 0.4064)
			(end -0.7874 -0.4064)
			(stroke
				(width 0.1524)
				(type default)
			)
			(layer "F.SilkS")
		)
		(fp_line
			(start 0.7874 -0.4064)
			(end 0.7874 0.4064)
			(stroke
				(width 0.1524)
				(type default)
			)
			(layer "F.SilkS")
		)
		(fp_line
			(start 0.7874 0.4064)
			(end -0.7874 0.4064)
			(stroke
				(width 0.1524)
				(type default)
			)
			(layer "F.SilkS")
		)
		(fp_line
			(start -0.67945 -0.305054)
			(end -0.12065 -0.305054)
			(stroke
				(width 0.1)
				(type default)
			)
			(layer "F.Fab")
		)
		(fp_line
			(start -0.67945 0.3048)
			(end -0.67945 -0.305054)
			(stroke
				(width 0.1)
				(type default)
			)
			(layer "F.Fab")
		)
		(fp_line
			(start -0.12065 -0.305054)
			(end -0.12065 -0.2794)
			(stroke
				(width 0.1)
				(type default)
			)
			(layer "F.Fab")
		)
		(fp_line
			(start -0.12065 -0.2794)
			(end 0.12065 -0.2794)
			(stroke
				(width 0.1)
				(type default)
			)
			(layer "F.Fab")
		)
		(fp_line
			(start -0.12065 0.2794)
			(end -0.12065 0.3048)
			(stroke
				(width 0.1)
				(type default)
			)
			(layer "F.Fab")
		)
		(fp_line
			(start -0.12065 0.3048)
			(end -0.67945 0.3048)
			(stroke
				(width 0.1)
				(type default)
			)
			(layer "F.Fab")
		)
		(fp_line
			(start 0.120396 0.2794)
			(end -0.12065 0.2794)
			(stroke
				(width 0.1)
				(type default)
			)
			(layer "F.Fab")
		)
		(fp_line
			(start 0.120396 0.3048)
			(end 0.120396 0.2794)
			(stroke
				(width 0.1)
				(type default)
			)
			(layer "F.Fab")
		)
		(fp_line
			(start 0.12065 -0.3048)
			(end 0.67945 -0.3048)
			(stroke
				(width 0.1)
				(type default)
			)
			(layer "F.Fab")
		)
		(fp_line
			(start 0.12065 -0.2794)
			(end 0.12065 -0.3048)
			(stroke
				(width 0.1)
				(type default)
			)
			(layer "F.Fab")
		)
		(fp_line
			(start 0.67945 -0.3048)
			(end 0.67945 0.3048)
			(stroke
				(width 0.1)
				(type default)
			)
			(layer "F.Fab")
		)
		(fp_line
			(start 0.67945 0.3048)
			(end 0.120396 0.3048)
			(stroke
				(width 0.1)
				(type default)
			)
			(layer "F.Fab")
		)
		(pad "1" smd circle
			(at -0.40005 0)
			(size 0 0)
			(layers "F.Cu" "F.Mask" "F.Paste")
			(net "P3V3_AUX")
		)
		(pad "2" smd circle
			(at 0.40005 0)
			(size 0 0)
			(layers "F.Cu" "F.Mask" "F.Paste")
			(net "GPU_BASE_STBY_EN")
		)
	)
	(footprint ""
		(layer "F.Cu")
		(at 309.522622 -30.343348 180)
		(property "Reference" "R1450"
			(at 0 0 180)
			(layer "F.SilkS")
			(hide yes)
			(effects
				(font
					(size 1.27 1.27)
				)
			)
		)
		(property "Value" ""
			(at 0 0 180)
			(layer "F.Fab")
			(effects
				(font
					(size 1.27 1.27)
				)
			)
		)
		(duplicate_pad_numbers_are_jumpers no)
		(fp_line
			(start 0.7874 0.4064)
			(end -0.7874 0.4064)
			(stroke
				(width 0.1524)
				(type default)
			)
			(layer "F.SilkS")
		)
		(fp_line
			(start 0.7874 -0.4064)
			(end 0.7874 0.4064)
			(stroke
				(width 0.1524)
				(type default)
			)
			(layer "F.SilkS")
		)
		(fp_line
			(start -0.7874 0.4064)
			(end -0.7874 -0.4064)
			(stroke
				(width 0.1524)
				(type default)
			)
			(layer "F.SilkS")
		)
		(fp_line
			(start -0.7874 -0.4064)
			(end 0.7874 -0.4064)
			(stroke
				(width 0.1524)
				(type default)
			)
			(layer "F.SilkS")
		)
		(fp_line
			(start 0.67945 0.3048)
			(end 0.120396 0.3048)
			(stroke
				(width 0.1)
				(type default)
			)
			(layer "F.Fab")
		)
		(fp_line
			(start 0.67945 -0.3048)
			(end 0.67945 0.3048)
			(stroke
				(width 0.1)
				(type default)
			)
			(layer "F.Fab")
		)
		(fp_line
			(start 0.12065 -0.2794)
			(end 0.12065 -0.3048)
			(stroke
				(width 0.1)
				(type default)
			)
			(layer "F.Fab")
		)
		(fp_line
			(start 0.12065 -0.3048)
			(end 0.67945 -0.3048)
			(stroke
				(width 0.1)
				(type default)
			)
			(layer "F.Fab")
		)
		(fp_line
			(start 0.120396 0.3048)
			(end 0.120396 0.2794)
			(stroke
				(width 0.1)
				(type default)
			)
			(layer "F.Fab")
		)
		(fp_line
			(start 0.120396 0.2794)
			(end -0.12065 0.2794)
			(stroke
				(width 0.1)
				(type default)
			)
			(layer "F.Fab")
		)
		(fp_line
			(start -0.12065 0.3048)
			(end -0.67945 0.3048)
			(stroke
				(width 0.1)
				(type default)
			)
			(layer "F.Fab")
		)
		(fp_line
			(start -0.12065 0.2794)
			(end -0.12065 0.3048)
			(stroke
				(width 0.1)
				(type default)
			)
			(layer "F.Fab")
		)
		(fp_line
			(start -0.12065 -0.2794)
			(end 0.12065 -0.2794)
			(stroke
				(width 0.1)
				(type default)
			)
			(layer "F.Fab")
		)
		(fp_line
			(start -0.12065 -0.305054)
			(end -0.12065 -0.2794)
			(stroke
				(width 0.1)
				(type default)
			)
			(layer "F.Fab")
		)
		(fp_line
			(start -0.67945 0.3048)
			(end -0.67945 -0.305054)
			(stroke
				(width 0.1)
				(type default)
			)
			(layer "F.Fab")
		)
		(fp_line
			(start -0.67945 -0.305054)
			(end -0.12065 -0.305054)
			(stroke
				(width 0.1)
				(type default)
			)
			(layer "F.Fab")
		)
		(pad "1" smd circle
			(at -0.40005 0 180)
			(size 0 0)
			(layers "F.Cu" "F.Mask" "F.Paste")
			(net "P3V3_AUX")
		)
		(pad "2" smd circle
			(at 0.40005 0 180)
			(size 0 0)
			(layers "F.Cu" "F.Mask" "F.Paste")
			(net "FM_THROTTLE_N")
		)
	)
)
